# T6G (Grand Teton) — schematic netlist excerpt (pin names and nets, part order shuffled) for the footprints in the layout excerpt that follows; sources: Cadence DE-HDL packaged netlist, KiCad conversion of 04192023_DAF0TMB3IC0_F0TG_MB_C_brd_V02_OCP.brd

H91  HOLE  EMPTY  pkg TH  page 230 : \1\ = GND
PC258  Q_CAP  0.022UF 25V 10% X7R  pkg 0402  page 209 : A = PVDD18_S5_P0_REF ; B = GND
R3276  Q_RES  1K 1% EMPTY  pkg 0402LF  page 111 : A = FM_P2E_FGA ; B = GND
R925  Q_RES  4.7K 5% CHIP  pkg 0201LF  page 353 : A = P1V8_CPU1_RT_1D ; B = MODE_RT_CPU1_P3

(kicad_pcb
	(version 20260206)
	(generator "pcbnew")
	(generator_version "10.0")
	(general
		(thickness 1.6)
		(legacy_teardrops no)
	)
	(paper "A4")
	(title_block
		(title "04192023_DAF0TMB3IC0_F0TG_MB_C_brd_V02_OCP.brd")
		(comment 1 "Grand Teton / footprints 1315-1318 of 8354")
	)
	(layers
		(0 "F.Cu" signal "TOP")
		(4 "In1.Cu" signal "GND")
		(6 "In2.Cu" signal "IN1")
		(8 "In3.Cu" signal "GND1")
		(10 "In4.Cu" signal "IN2")
		(12 "In5.Cu" signal "GND2")
		(14 "In6.Cu" signal "IN3")
		(16 "In7.Cu" signal "GND3")
		(18 "In8.Cu" signal "VCC")
		(20 "In9.Cu" signal "VCC1")
		(22 "In10.Cu" signal "GND4")
		(24 "In11.Cu" signal "IN4")
		(26 "In12.Cu" signal "GND5")
		(28 "In13.Cu" signal "IN5")
		(30 "In14.Cu" signal "GND6")
		(32 "In15.Cu" signal "IN6")
		(34 "In16.Cu" signal "GND7")
		(2 "B.Cu" signal "BOTTOM")
		(9 "F.Adhes" user "F.Adhesive")
		(11 "B.Adhes" user "B.Adhesive")
		(13 "F.Paste" user "Package Geometry/Pastemask Top")
		(15 "B.Paste" user "Package Geometry/Pastemask Bottom")
		(5 "F.SilkS" user "Ref Des/Silkscreen Top")
		(7 "B.SilkS" user "Ref Des/Silkscreen Bottom")
		(1 "F.Mask" user "Board Geometry/Soldermask Top")
		(3 "B.Mask" user "Board Geometry/Soldermask Bottom")
		(17 "Dwgs.User" user "User.Drawings")
		(19 "Cmts.User" user "User.Comments")
		(21 "Eco1.User" user "User.Eco1")
		(23 "Eco2.User" user "User.Eco2")
		(25 "Edge.Cuts" user "Board Geometry/Outline")
		(27 "Margin" user)
		(31 "F.CrtYd" user "Package Geometry/Place Bound Top")
		(29 "B.CrtYd" user "Package Geometry/Place Bound Bottom")
		(35 "F.Fab" user "Ref Des/Assembly Top")
		(33 "B.Fab" user "Ref Des/Assembly Bottom")
	)
	(footprint ""
		(layer "F.Cu")
		(at 113.34496 -395.441932 -90)
		(property "Reference" "R925"
			(at 0 0 270)
			(layer "F.SilkS")
			(hide yes)
			(effects
				(font
					(size 1.27 1.27)
				)
			)
		)
		(property "Value" ""
			(at 0 0 270)
			(layer "F.Fab")
			(effects
				(font
					(size 1.27 1.27)
				)
			)
		)
		(duplicate_pad_numbers_are_jumpers no)
		(fp_line
			(start -0.32512 0.175006)
			(end -0.32512 -0.175006)
			(stroke
				(width 0.1)
				(type default)
			)
			(layer "F.Fab")
		)
		(fp_line
			(start 0.32512 0.175006)
			(end -0.32512 0.175006)
			(stroke
				(width 0.1)
				(type default)
			)
			(layer "F.Fab")
		)
		(fp_line
			(start -0.32512 -0.175006)
			(end 0.32512 -0.175006)
			(stroke
				(width 0.1)
				(type default)
			)
			(layer "F.Fab")
		)
		(fp_line
			(start 0.32512 -0.175006)
			(end 0.32512 0.175006)
			(stroke
				(width 0.1)
				(type default)
			)
			(layer "F.Fab")
		)
		(pad "1" smd rect
			(at -0.2667 0 270)
			(size 0.3048 0.381)
			(layers "F.Cu" "F.Mask" "F.Paste")
			(net "P1V8_CPU1_RT_1D")
		)
		(pad "2" smd rect
			(at 0.2667 0 90)
			(size 0.3048 0.381)
			(layers "F.Cu" "F.Mask" "F.Paste")
			(net "MODE_RT_CPU1_P3")
		)
	)
	(footprint ""
		(layer "F.Cu")
		(at 6.999986 -22.29993)
		(property "Reference" "H91"
			(at -5.190744 -5.784596 0)
			(unlocked yes)
			(layer "F.SilkS")
			(effects
				(font
					(size 0.7874 0.5842)
					(thickness 0.1524)
				)
				(justify left)
			)
		)
		(property "Value" ""
			(at 0 0 0)
			(layer "F.Fab")
			(effects
				(font
					(size 1.27 1.27)
				)
			)
		)
		(duplicate_pad_numbers_are_jumpers no)
		(pad "1" thru_hole circle
			(at 0 0)
			(size 10.0076 10.0076)
			(drill 5.6134)
			(layers "*.Cu" "*.Mask")
			(remove_unused_layers no)
			(net "GND")
			(clearance -1.9431)
		)
	)
	(footprint ""
		(layer "F.Cu")
		(at 31.585662 -419.249098 -90)
		(property "Reference" "R3276"
			(at 0 0 270)
			(layer "F.SilkS")
			(hide yes)
			(effects
				(font
					(size 1.27 1.27)
				)
			)
		)
		(property "Value" ""
			(at 0 0 270)
			(layer "F.Fab")
			(effects
				(font
					(size 1.27 1.27)
				)
			)
		)
		(duplicate_pad_numbers_are_jumpers no)
		(fp_line
			(start -0.7874 0.4064)
			(end -0.7874 -0.4064)
			(stroke
				(width 0.1524)
				(type default)
			)
			(layer "F.SilkS")
		)
		(fp_line
			(start 0.7874 0.4064)
			(end -0.7874 0.4064)
			(stroke
				(width 0.1524)
				(type default)
			)
			(layer "F.SilkS")
		)
		(fp_line
			(start -0.7874 -0.4064)
			(end 0.7874 -0.4064)
			(stroke
				(width 0.1524)
				(type default)
			)
			(layer "F.SilkS")
		)
		(fp_line
			(start 0.7874 -0.4064)
			(end 0.7874 0.4064)
			(stroke
				(width 0.1524)
				(type default)
			)
			(layer "F.SilkS")
		)
		(fp_line
			(start -0.67945 0.3048)
			(end -0.67945 -0.305054)
			(stroke
				(width 0.1)
				(type default)
			)
			(layer "F.Fab")
		)
		(fp_line
			(start -0.12065 0.3048)
			(end -0.67945 0.3048)
			(stroke
				(width 0.1)
				(type default)
			)
			(layer "F.Fab")
		)
		(fp_line
			(start 0.120396 0.3048)
			(end 0.120396 0.2794)
			(stroke
				(width 0.1)
				(type default)
			)
			(layer "F.Fab")
		)
		(fp_line
			(start 0.67945 0.3048)
			(end 0.120396 0.3048)
			(stroke
				(width 0.1)
				(type default)
			)
			(layer "F.Fab")
		)
		(fp_line
			(start -0.12065 0.2794)
			(end -0.12065 0.3048)
			(stroke
				(width 0.1)
				(type default)
			)
			(layer "F.Fab")
		)
		(fp_line
			(start 0.120396 0.2794)
			(end -0.12065 0.2794)
			(stroke
				(width 0.1)
				(type default)
			)
			(layer "F.Fab")
		)
		(fp_line
			(start -0.12065 -0.2794)
			(end 0.12065 -0.2794)
			(stroke
				(width 0.1)
				(type default)
			)
			(layer "F.Fab")
		)
		(fp_line
			(start 0.12065 -0.2794)
			(end 0.12065 -0.3048)
			(stroke
				(width 0.1)
				(type default)
			)
			(layer "F.Fab")
		)
		(fp_line
			(start 0.12065 -0.3048)
			(end 0.67945 -0.3048)
			(stroke
				(width 0.1)
				(type default)
			)
			(layer "F.Fab")
		)
		(fp_line
			(start 0.67945 -0.3048)
			(end 0.67945 0.3048)
			(stroke
				(width 0.1)
				(type default)
			)
			(layer "F.Fab")
		)
		(fp_line
			(start -0.67945 -0.305054)
			(end -0.12065 -0.305054)
			(stroke
				(width 0.1)
				(type default)
			)
			(layer "F.Fab")
		)
		(fp_line
			(start -0.12065 -0.305054)
			(end -0.12065 -0.2794)
			(stroke
				(width 0.1)
				(type default)
			)
			(layer "F.Fab")
		)
		(pad "1" smd circle
			(at -0.40005 0 270)
			(size 0 0)
			(layers "F.Cu" "F.Mask" "F.Paste")
			(net "FM_P2E_FGA")
		)
		(pad "2" smd circle
			(at 0.40005 0 270)
			(size 0 0)
			(layers "F.Cu" "F.Mask" "F.Paste")
			(net "GND")
		)
	)
	(footprint ""
		(layer "F.Cu")
		(at 330.775564 -140.414502 180)
		(property "Reference" "PC258"
			(at 0 0 180)
			(layer "F.SilkS")
			(hide yes)
			(effects
				(font
					(size 1.27 1.27)
				)
			)
		)
		(property "Value" ""
			(at 0 0 180)
			(layer "F.Fab")
			(effects
				(font
					(size 1.27 1.27)
				)
			)
		)
		(duplicate_pad_numbers_are_jumpers no)
		(fp_line
			(start 0.7874 0.4064)
			(end -0.7874 0.4064)
			(stroke
				(width 0.1524)
				(type default)
			)
			(layer "F.SilkS")
		)
		(fp_line
			(start 0.7874 -0.4064)
			(end 0.7874 0.4064)
			(stroke
				(width 0.1524)
				(type default)
			)
			(layer "F.SilkS")
		)
		(fp_line
			(start -0.7874 0.4064)
			(end -0.7874 -0.4064)
			(stroke
				(width 0.1524)
				(type default)
			)
			(layer "F.SilkS")
		)
		(fp_line
			(start -0.7874 -0.4064)
			(end 0.7874 -0.4064)
			(stroke
				(width 0.1524)
				(type default)
			)
			(layer "F.SilkS")
		)
		(fp_line
			(start 0.67945 0.3048)
			(end 0.120396 0.3048)
			(stroke
				(width 0.1)
				(type default)
			)
			(layer "F.Fab")
		)
		(fp_line
			(start 0.67945 -0.3048)
			(end 0.67945 0.3048)
			(stroke
				(width 0.1)
				(type default)
			)
			(layer "F.Fab")
		)
		(fp_line
			(start 0.12065 -0.2794)
			(end 0.12065 -0.3048)
			(stroke
				(width 0.1)
				(type default)
			)
			(layer "F.Fab")
		)
		(fp_line
			(start 0.12065 -0.3048)
			(end 0.67945 -0.3048)
			(stroke
				(width 0.1)
				(type default)
			)
			(layer "F.Fab")
		)
		(fp_line
			(start 0.120396 0.3048)
			(end 0.120396 0.2794)
			(stroke
				(width 0.1)
				(type default)
			)
			(layer "F.Fab")
		)
		(fp_line
			(start 0.120396 0.2794)
			(end -0.12065 0.2794)
			(stroke
				(width 0.1)
				(type default)
			)
			(layer "F.Fab")
		)
		(fp_line
			(start -0.12065 0.3048)
			(end -0.67945 0.3048)
			(stroke
				(width 0.1)
				(type default)
			)
			(layer "F.Fab")
		)
		(fp_line
			(start -0.12065 0.2794)
			(end -0.12065 0.3048)
			(stroke
				(width 0.1)
				(type default)
			)
			(layer "F.Fab")
		)
		(fp_line
			(start -0.12065 -0.2794)
			(end 0.12065 -0.2794)
			(stroke
				(width 0.1)
				(type default)
			)
			(layer "F.Fab")
		)
		(fp_line
			(start -0.12065 -0.305054)
			(end -0.12065 -0.2794)
			(stroke
				(width 0.1)
				(type default)
			)
			(layer "F.Fab")
		)
		(fp_line
			(start -0.67945 0.3048)
			(end -0.67945 -0.305054)
			(stroke
				(width 0.1)
				(type default)
			)
			(layer "F.Fab")
		)
		(fp_line
			(start -0.67945 -0.305054)
			(end -0.12065 -0.305054)
			(stroke
				(width 0.1)
				(type default)
			)
			(layer "F.Fab")
		)
		(pad "1" smd circle
			(at -0.40005 0 180)
			(size 0 0)
			(layers "F.Cu" "F.Mask" "F.Paste")
			(net "PVDD18_S5_P0_REF")
		)
		(pad "2" smd circle
			(at 0.40005 0 180)
			(size 0 0)
			(layers "F.Cu" "F.Mask" "F.Paste")
			(net "GND")
		)
	)
)
